(kicad_pcb
	(version 20260206)
	(generator "pcbnew")
	(generator_version "10.0")
	(general
		(thickness 1.6)
		(legacy_teardrops no)
	)
	(paper "A4")
	(title_block
		(title "Wiwynn_Tioga_Pass_MB.brd")
		(comment 1 "Tioga Pass / footprints 4100-4106 of 4770")
	)
	(layers
		(0 "F.Cu" signal "TOP")
		(4 "In1.Cu" signal "L2GND")
		(6 "In2.Cu" signal "L3")
		(8 "In3.Cu" signal "L4GND")
		(10 "In4.Cu" signal "L5")
		(12 "In5.Cu" signal "L6GND")
		(14 "In6.Cu" signal "L7VCC")
		(16 "In7.Cu" signal "L8VCC")
		(18 "In8.Cu" signal "L9GND")
		(20 "In9.Cu" signal "L10")
		(22 "In10.Cu" signal "L11GND")
		(24 "In11.Cu" signal "L12")
		(26 "In12.Cu" signal "L13GND")
		(2 "B.Cu" signal "BOTTOM")
		(9 "F.Adhes" user "F.Adhesive")
		(11 "B.Adhes" user "B.Adhesive")
		(13 "F.Paste" user "Package Geometry/Pastemask Top")
		(15 "B.Paste" user "Package Geometry/Pastemask Bottom")
		(5 "F.SilkS" user "Ref Des/Silkscreen Top")
		(7 "B.SilkS" user "Ref Des/Silkscreen Bottom")
		(1 "F.Mask" user "Board Geometry/Soldermask Top")
		(3 "B.Mask" user "Board Geometry/Soldermask Bottom")
		(17 "Dwgs.User" user "User.Drawings")
		(19 "Cmts.User" user "User.Comments")
		(21 "Eco1.User" user "User.Eco1")
		(23 "Eco2.User" user "User.Eco2")
		(25 "Edge.Cuts" user "Board Geometry/Outline")
		(27 "Margin" user)
		(31 "F.CrtYd" user "Package Geometry/Place Bound Top")
		(29 "B.CrtYd" user "Package Geometry/Place Bound Bottom")
		(35 "F.Fab" user "Ref Des/Assembly Top")
		(33 "B.Fab" user "Ref Des/Assembly Bottom")
	)
	(footprint ""
		(layer "B.Cu")
		(at 481.2665 -30.226 -90)
		(property "Reference" "C2T30"
			(at 0 0 90)
			(layer "B.SilkS")
			(hide yes)
			(effects
				(font
					(size 1.27 1.27)
				)
				(justify mirror)
			)
		)
		(property "Value" ""
			(at 0 0 90)
			(layer "B.Fab")
			(effects
				(font
					(size 1.27 1.27)
				)
				(justify mirror)
			)
		)
		(duplicate_pad_numbers_are_jumpers no)
		(fp_poly
			(pts
				(xy -0.3048 -0.1016) (xy -0.3048 0.9906) (xy 0.3048 0.9906) (xy 0.3048 -0.1016)
			)
			(stroke
				(width 0)
				(type default)
			)
			(fill no)
			(layer "B.CrtYd")
		)
		(fp_line
			(start -0.3048 0.9906)
			(end -0.3048 -0.1016)
			(stroke
				(width 0.1)
				(type default)
			)
			(layer "B.Fab")
		)
		(fp_line
			(start 0.3048 0.9906)
			(end -0.3048 0.9906)
			(stroke
				(width 0.1)
				(type default)
			)
			(layer "B.Fab")
		)
		(fp_line
			(start -0.3048 -0.1016)
			(end 0.3048 -0.1016)
			(stroke
				(width 0.1)
				(type default)
			)
			(layer "B.Fab")
		)
		(fp_line
			(start 0.3048 -0.1016)
			(end 0.3048 0.9906)
			(stroke
				(width 0.1)
				(type default)
			)
			(layer "B.Fab")
		)
		(pad "1" smd rect
			(at 0 0 90)
			(size 0.508 0.508)
			(layers "B.Cu" "B.Mask" "B.Paste")
			(net "P3V3_STBY_MNG")
		)
		(pad "2" smd rect
			(at 0 0.889 90)
			(size 0.508 0.508)
			(layers "B.Cu" "B.Mask" "B.Paste")
			(net "GND")
		)
		(zone
			(layer "B.Cu")
			(hatch none 0.5)
			(connect_pads
				(clearance 0)
			)
			(min_thickness 0.25)
			(keepout
				(tracks not_allowed)
				(vias allowed)
				(pads allowed)
				(copperpour not_allowed)
				(footprints allowed)
			)
			(placement
				(enabled no)
				(sheetname "")
			)
			(fill
				(thermal_gap 0.5)
				(thermal_bridge_width 0.5)
				(island_removal_mode 0)
			)
			(polygon
				(pts
					(xy 480.6315 -29.972) (xy 480.6315 -30.48) (xy 481.0125 -30.48) (xy 481.0125 -29.972)
				)
			)
		)
		(zone
			(layer "B.Cu")
			(hatch none 0.5)
			(connect_pads
				(clearance 0)
			)
			(min_thickness 0.25)
			(keepout
				(tracks allowed)
				(vias not_allowed)
				(pads allowed)
				(copperpour not_allowed)
				(footprints allowed)
			)
			(placement
				(enabled no)
				(sheetname "")
			)
			(fill
				(thermal_gap 0.5)
				(thermal_bridge_width 0.5)
				(island_removal_mode 0)
			)
			(polygon
				(pts
					(xy 481.0125 -29.972) (xy 481.0125 -30.48) (xy 480.6315 -30.48) (xy 480.6315 -29.972)
				)
			)
		)
	)
	(footprint ""
		(layer "B.Cu")
		(at 435.381654 -141.002512 180)
		(property "Reference" "C2L49"
			(at 0 0 0)
			(layer "B.SilkS")
			(hide yes)
			(effects
				(font
					(size 1.27 1.27)
				)
				(justify mirror)
			)
		)
		(property "Value" ""
			(at 0 0 0)
			(layer "B.Fab")
			(effects
				(font
					(size 1.27 1.27)
				)
				(justify mirror)
			)
		)
		(duplicate_pad_numbers_are_jumpers no)
		(fp_poly
			(pts
				(xy -0.3048 -0.1016) (xy -0.3048 0.9906) (xy 0.3048 0.9906) (xy 0.3048 -0.1016)
			)
			(stroke
				(width 0)
				(type default)
			)
			(fill no)
			(layer "B.CrtYd")
		)
		(fp_line
			(start 0.3048 0.9906)
			(end -0.3048 0.9906)
			(stroke
				(width 0.1)
				(type default)
			)
			(layer "B.Fab")
		)
		(fp_line
			(start 0.3048 -0.1016)
			(end 0.3048 0.9906)
			(stroke
				(width 0.1)
				(type default)
			)
			(layer "B.Fab")
		)
		(fp_line
			(start -0.3048 0.9906)
			(end -0.3048 -0.1016)
			(stroke
				(width 0.1)
				(type default)
			)
			(layer "B.Fab")
		)
		(fp_line
			(start -0.3048 -0.1016)
			(end 0.3048 -0.1016)
			(stroke
				(width 0.1)
				(type default)
			)
			(layer "B.Fab")
		)
		(pad "1" smd rect
			(at 0 0)
			(size 0.508 0.508)
			(layers "B.Cu" "B.Mask" "B.Paste")
			(net "SATA6G_S1_RX_C_DP")
		)
		(pad "2" smd rect
			(at 0 0.889)
			(size 0.508 0.508)
			(layers "B.Cu" "B.Mask" "B.Paste")
			(net "SATA6G_S1_RX_DP")
		)
		(zone
			(layer "B.Cu")
			(hatch none 0.5)
			(connect_pads
				(clearance 0)
			)
			(min_thickness 0.25)
			(keepout
				(tracks not_allowed)
				(vias allowed)
				(pads allowed)
				(copperpour not_allowed)
				(footprints allowed)
			)
			(placement
				(enabled no)
				(sheetname "")
			)
			(fill
				(thermal_gap 0.5)
				(thermal_bridge_width 0.5)
				(island_removal_mode 0)
			)
			(polygon
				(pts
					(xy 435.127654 -141.637512) (xy 435.635654 -141.637512) (xy 435.635654 -141.256512) (xy 435.127654 -141.256512)
				)
			)
		)
		(zone
			(layer "B.Cu")
			(hatch none 0.5)
			(connect_pads
				(clearance 0)
			)
			(min_thickness 0.25)
			(keepout
				(tracks allowed)
				(vias not_allowed)
				(pads allowed)
				(copperpour not_allowed)
				(footprints allowed)
			)
			(placement
				(enabled no)
				(sheetname "")
			)
			(fill
				(thermal_gap 0.5)
				(thermal_bridge_width 0.5)
				(island_removal_mode 0)
			)
			(polygon
				(pts
					(xy 435.127654 -141.256512) (xy 435.635654 -141.256512) (xy 435.635654 -141.637512) (xy 435.127654 -141.637512)
				)
			)
		)
	)
	(footprint ""
		(layer "B.Cu")
		(at 477.29521 -150.174706)
		(property "Reference" "Q1L2"
			(at -1.8796 2.23647 0)
			(unlocked yes)
			(layer "B.SilkS")
			(effects
				(font
					(size 0.7874 0.5842)
					(thickness 0.1524)
				)
				(justify left mirror)
			)
		)
		(property "Value" ""
			(at 0 0 0)
			(layer "B.Fab")
			(effects
				(font
					(size 1.27 1.27)
				)
				(justify mirror)
			)
		)
		(duplicate_pad_numbers_are_jumpers no)
		(fp_circle
			(center 0.508 -0.7874)
			(end 0.635 -0.7874)
			(stroke
				(width 0.254)
				(type default)
			)
			(fill no)
			(layer "B.SilkS")
		)
		(fp_poly
			(pts
				(xy -0.2159 1.7526) (xy -1.5621 1.7526) (xy -1.5621 -0.4572) (xy -0.2159 -0.4572)
			)
			(stroke
				(width 0)
				(type default)
			)
			(fill no)
			(layer "B.CrtYd")
		)
		(fp_line
			(start -1.5621 -0.45466)
			(end -0.2159 -0.45466)
			(stroke
				(width 0.1)
				(type default)
			)
			(layer "B.Fab")
		)
		(fp_line
			(start -1.5621 1.75514)
			(end -1.5621 -0.45466)
			(stroke
				(width 0.1)
				(type default)
			)
			(layer "B.Fab")
		)
		(fp_line
			(start -0.2159 -0.45466)
			(end -0.2159 1.75514)
			(stroke
				(width 0.1)
				(type default)
			)
			(layer "B.Fab")
		)
		(fp_line
			(start -0.2159 1.75514)
			(end -1.5621 1.75514)
			(stroke
				(width 0.1)
				(type default)
			)
			(layer "B.Fab")
		)
		(fp_circle
			(center 0.508 -0.7874)
			(end 0.635 -0.7874)
			(stroke
				(width 0.254)
				(type default)
			)
			(fill no)
			(layer "B.Fab")
		)
		(pad "1" smd rect
			(at 0 0 180)
			(size 1.016 0.381)
			(layers "B.Cu" "B.Mask" "B.Paste")
			(net "P5V_STBY_DBG")
		)
		(pad "2" smd rect
			(at 0 0.65024 180)
			(size 1.016 0.381)
			(layers "B.Cu" "B.Mask" "B.Paste")
			(net "FM_CPLD_DBG_PWR_EN")
		)
		(pad "3" smd rect
			(at 0 1.30048 180)
			(size 1.016 0.381)
			(layers "B.Cu" "B.Mask" "B.Paste")
			(net "FM_CPLD_DBG_PWR_EN")
		)
		(pad "4" smd rect
			(at -1.778 1.30048 180)
			(size 1.016 0.381)
			(layers "B.Cu" "B.Mask" "B.Paste")
			(net "GND")
		)
		(pad "5" smd rect
			(at -1.778 0.65024 180)
			(size 1.016 0.381)
			(layers "B.Cu" "B.Mask" "B.Paste")
			(net "FM_CPLD_DBG_PWR_EN_R_N")
		)
		(pad "6" smd rect
			(at -1.778 0 180)
			(size 1.016 0.381)
			(layers "B.Cu" "B.Mask" "B.Paste")
			(net "P5V_STBY")
		)
		(zone
			(layer "B.Cu")
			(hatch none 0.5)
			(connect_pads
				(clearance 0)
			)
			(min_thickness 0.25)
			(keepout
				(tracks allowed)
				(vias not_allowed)
				(pads allowed)
				(copperpour not_allowed)
				(footprints allowed)
			)
			(placement
				(enabled no)
				(sheetname "")
			)
			(fill
				(thermal_gap 0.5)
				(thermal_bridge_width 0.5)
				(island_removal_mode 0)
			)
			(polygon
				(pts
					(xy 476.02521 -150.365206) (xy 475.00921 -150.365206) (xy 475.00921 -148.676106) (xy 476.02521 -148.676106)
				)
			)
		)
		(zone
			(layer "B.Cu")
			(hatch none 0.5)
			(connect_pads
				(clearance 0)
			)
			(min_thickness 0.25)
			(keepout
				(tracks allowed)
				(vias not_allowed)
				(pads allowed)
				(copperpour not_allowed)
				(footprints allowed)
			)
			(placement
				(enabled no)
				(sheetname "")
			)
			(fill
				(thermal_gap 0.5)
				(thermal_bridge_width 0.5)
				(island_removal_mode 0)
			)
			(polygon
				(pts
					(xy 477.80321 -150.365206) (xy 476.78721 -150.365206) (xy 476.78721 -148.676106) (xy 477.80321 -148.676106)
				)
			)
		)
	)
	(footprint ""
		(layer "B.Cu")
		(at 276.933152 -125.69444 90)
		(property "Reference" "C4M5"
			(at -1.76911 0.942848 0)
			(unlocked yes)
			(layer "B.SilkS")
			(effects
				(font
					(size 0.7874 0.5842)
					(thickness 0.1524)
				)
				(justify mirror)
			)
		)
		(property "Value" ""
			(at 0 0 90)
			(layer "B.Fab")
			(effects
				(font
					(size 1.27 1.27)
				)
				(justify mirror)
			)
		)
		(duplicate_pad_numbers_are_jumpers no)
		(fp_rect
			(start 0.500126 1.598422)
			(end -0.500126 -0.201422)
			(stroke
				(width 0)
				(type default)
			)
			(fill no)
			(layer "B.CrtYd")
		)
		(fp_line
			(start 0.500126 -0.201422)
			(end -0.500126 -0.201422)
			(stroke
				(width 0.1)
				(type default)
			)
			(layer "B.Fab")
		)
		(fp_line
			(start -0.500126 -0.201422)
			(end -0.500126 1.598422)
			(stroke
				(width 0.1)
				(type default)
			)
			(layer "B.Fab")
		)
		(fp_line
			(start 0.500126 1.598422)
			(end 0.500126 -0.201422)
			(stroke
				(width 0.1)
				(type default)
			)
			(layer "B.Fab")
		)
		(fp_line
			(start -0.500126 1.598422)
			(end 0.500126 1.598422)
			(stroke
				(width 0.1)
				(type default)
			)
			(layer "B.Fab")
		)
		(pad "1" smd rect
			(at 0 0)
			(size 0.889 0.9906)
			(layers "B.Cu" "B.Mask" "B.Paste")
			(net "PVDDQ_DEF")
		)
		(pad "2" smd rect
			(at 0 1.397)
			(size 0.889 0.9906)
			(layers "B.Cu" "B.Mask" "B.Paste")
			(net "GND")
		)
		(zone
			(layer "B.Cu")
			(hatch none 0.5)
			(connect_pads
				(clearance 0)
			)
			(min_thickness 0.25)
			(keepout
				(tracks allowed)
				(vias not_allowed)
				(pads allowed)
				(copperpour not_allowed)
				(footprints allowed)
			)
			(placement
				(enabled no)
				(sheetname "")
			)
			(fill
				(thermal_gap 0.5)
				(thermal_bridge_width 0.5)
				(island_removal_mode 0)
			)
			(polygon
				(pts
					(xy 277.885652 -126.18974) (xy 277.377652 -126.18974) (xy 277.377652 -125.19914) (xy 277.885652 -125.19914)
				)
			)
		)
		(zone
			(layer "B.Cu")
			(hatch none 0.5)
			(connect_pads
				(clearance 0)
			)
			(min_thickness 0.25)
			(keepout
				(tracks not_allowed)
				(vias allowed)
				(pads allowed)
				(copperpour not_allowed)
				(footprints allowed)
			)
			(placement
				(enabled no)
				(sheetname "")
			)
			(fill
				(thermal_gap 0.5)
				(thermal_bridge_width 0.5)
				(island_removal_mode 0)
			)
			(polygon
				(pts
					(xy 277.885652 -126.18974) (xy 277.377652 -126.18974) (xy 277.377652 -125.19914) (xy 277.885652 -125.19914)
				)
			)
		)
	)
	(footprint ""
		(layer "B.Cu")
		(at 94.313248 -12.999212 90)
		(property "Reference" "C5G118"
			(at -1.64973 0.78994 180)
			(unlocked yes)
			(layer "B.SilkS")
			(effects
				(font
					(size 0.7874 0.5842)
					(thickness 0.1524)
				)
				(justify mirror)
			)
		)
		(property "Value" ""
			(at 0 0 90)
			(layer "B.Fab")
			(effects
				(font
					(size 1.27 1.27)
				)
				(justify mirror)
			)
		)
		(duplicate_pad_numbers_are_jumpers no)
		(fp_rect
			(start -0.7239 -0.2159)
			(end 0.7239 1.9939)
			(stroke
				(width 0)
				(type default)
			)
			(fill no)
			(layer "B.CrtYd")
		)
		(fp_line
			(start 0.7239 -0.2159)
			(end 0.7239 1.9939)
			(stroke
				(width 0.1)
				(type default)
			)
			(layer "B.Fab")
		)
		(fp_line
			(start -0.7239 -0.2159)
			(end 0.7239 -0.2159)
			(stroke
				(width 0.1)
				(type default)
			)
			(layer "B.Fab")
		)
		(fp_line
			(start 0.7239 1.9939)
			(end -0.7239 1.9939)
			(stroke
				(width 0.1)
				(type default)
			)
			(layer "B.Fab")
		)
		(fp_line
			(start -0.7239 1.9939)
			(end -0.7239 -0.2159)
			(stroke
				(width 0.1)
				(type default)
			)
			(layer "B.Fab")
		)
		(pad "1" smd rect
			(at 0 0 270)
			(size 1.27 1.016)
			(layers "B.Cu" "B.Mask" "B.Paste")
			(net "PVDDQ_GHJ")
		)
		(pad "2" smd rect
			(at 0 1.778 270)
			(size 1.27 1.016)
			(layers "B.Cu" "B.Mask" "B.Paste")
			(net "GND")
		)
		(zone
			(layer "B.Cu")
			(hatch none 0.5)
			(connect_pads
				(clearance 0)
			)
			(min_thickness 0.25)
			(keepout
				(tracks not_allowed)
				(vias allowed)
				(pads allowed)
				(copperpour not_allowed)
				(footprints allowed)
			)
			(placement
				(enabled no)
				(sheetname "")
			)
			(fill
				(thermal_gap 0.5)
				(thermal_bridge_width 0.5)
				(island_removal_mode 0)
			)
			(polygon
				(pts
					(xy 94.821248 -12.364212) (xy 95.583248 -12.364212) (xy 95.583248 -13.634212) (xy 94.821248 -13.634212)
				)
			)
		)
	)
	(footprint ""
		(layer "B.Cu")
		(at 156.19222 -121.4247 180)
		(property "Reference" "R7M8"
			(at 0 0 0)
			(layer "B.SilkS")
			(hide yes)
			(effects
				(font
					(size 1.27 1.27)
				)
				(justify mirror)
			)
		)
		(property "Value" ""
			(at 0 0 0)
			(layer "B.Fab")
			(effects
				(font
					(size 1.27 1.27)
				)
				(justify mirror)
			)
		)
		(duplicate_pad_numbers_are_jumpers no)
		(fp_poly
			(pts
				(xy 0.2794 -0.1016) (xy -0.2794 -0.1016) (xy -0.2794 0.9906) (xy 0.2794 0.9906)
			)
			(stroke
				(width 0)
				(type default)
			)
			(fill no)
			(layer "B.CrtYd")
		)
		(fp_line
			(start 0.2794 0.9906)
			(end -0.2794 0.9906)
			(stroke
				(width 0.1)
				(type default)
			)
			(layer "B.Fab")
		)
		(fp_line
			(start 0.2794 -0.1016)
			(end 0.2794 0.9906)
			(stroke
				(width 0.1)
				(type default)
			)
			(layer "B.Fab")
		)
		(fp_line
			(start -0.2794 0.9906)
			(end -0.2794 -0.1016)
			(stroke
				(width 0.1)
				(type default)
			)
			(layer "B.Fab")
		)
		(fp_line
			(start -0.2794 -0.1016)
			(end 0.2794 -0.1016)
			(stroke
				(width 0.1)
				(type default)
			)
			(layer "B.Fab")
		)
		(pad "1" smd rect
			(at 0 0)
			(size 0.508 0.508)
			(layers "B.Cu" "B.Mask" "B.Paste")
			(net "SMB_DDR_KLM_SDA_G_R")
		)
		(pad "2" smd rect
			(at 0 0.889)
			(size 0.508 0.508)
			(layers "B.Cu" "B.Mask" "B.Paste")
			(net "SMB_DDR_KLM_SDA_G")
		)
		(zone
			(layer "B.Cu")
			(hatch none 0.5)
			(connect_pads
				(clearance 0)
			)
			(min_thickness 0.25)
			(keepout
				(tracks not_allowed)
				(vias allowed)
				(pads allowed)
				(copperpour not_allowed)
				(footprints allowed)
			)
			(placement
				(enabled no)
				(sheetname "")
			)
			(fill
				(thermal_gap 0.5)
				(thermal_bridge_width 0.5)
				(island_removal_mode 0)
			)
			(polygon
				(pts
					(xy 155.93822 -122.0597) (xy 156.44622 -122.0597) (xy 156.44622 -121.6787) (xy 155.93822 -121.6787)
				)
			)
		)
		(zone
			(layer "B.Cu")
			(hatch none 0.5)
			(connect_pads
				(clearance 0)
			)
			(min_thickness 0.25)
			(keepout
				(tracks allowed)
				(vias not_allowed)
				(pads allowed)
				(copperpour not_allowed)
				(footprints allowed)
			)
			(placement
				(enabled no)
				(sheetname "")
			)
			(fill
				(thermal_gap 0.5)
				(thermal_bridge_width 0.5)
				(island_removal_mode 0)
			)
			(polygon
				(pts
					(xy 155.93822 -121.6787) (xy 156.44622 -121.6787) (xy 156.44622 -122.0597) (xy 155.93822 -122.0597)
				)
			)
		)
	)
	(footprint ""
		(layer "B.Cu")
		(at 187.071 -53.975)
		(property "Reference" "C4E8"
			(at 0 0 0)
			(layer "B.SilkS")
			(hide yes)
			(effects
				(font
					(size 1.27 1.27)
				)
				(justify mirror)
			)
		)
		(property "Value" "*"
			(at 0.0762 -6.2357 0)
			(unlocked yes)
			(layer "B.Fab")
			(hide yes)
			(effects
				(font
					(size 1.27 1.016)
					(thickness 0.1524)
				)
				(justify mirror)
			)
		)
		(property "Device Type" "SC22U16V5MX-4-GP_SMD-BCG5-SC22A"
			(at 0.0762 -8.2677 0)
			(unlocked yes)
			(layer "B.Fab")
			(hide yes)
			(effects
				(font
					(size 1.27 1.016)
					(thickness 0.1524)
				)
				(justify mirror)
			)
		)
		(duplicate_pad_numbers_are_jumpers no)
		(fp_line
			(start -0.635 0)
			(end 0.635 0)
			(stroke
				(width 0.508)
				(type default)
			)
			(layer "B.SilkS")
		)
		(fp_rect
			(start 0.9652 1.778)
			(end -0.9652 -1.778)
			(stroke
				(width 0)
				(type default)
			)
			(fill no)
			(layer "B.CrtYd")
		)
		(fp_poly
			(pts
				(xy 0.9652 -1.778) (xy -0.9652 -1.778) (xy -0.9652 1.778) (xy 0.9652 1.778)
			)
			(stroke
				(width 0)
				(type default)
			)
			(fill no)
			(layer "B.Fab")
		)
		(pad "1" smd rect
			(at 0 -0.9652 180)
			(size 1.397 1.143)
			(layers "B.Cu" "B.Mask" "B.Paste")
			(net "VR_FET_SW_P12V_STBY_PVCCIN_CPU0")
		)
		(pad "2" smd rect
			(at 0 0.9652 180)
			(size 1.397 1.143)
			(layers "B.Cu" "B.Mask" "B.Paste")
			(net "GND")
		)
	)
)
